(kicad_pcb
	(version 20260206)
	(generator "pcbnew")
	(generator_version "10.0")
	(general
		(thickness 1.6)
		(legacy_teardrops no)
	)
	(paper "A4")
	(title_block
		(title "v1-chassis-manager — T6M_CM_d_v01_1031_1645.brd")
		(comment 1 "Open CloudServer (Microsoft) / footprints 1542-1548 of 2512")
	)
	(layers
		(0 "F.Cu" signal "TOP")
		(4 "In1.Cu" signal "GND1")
		(6 "In2.Cu" signal "IN1")
		(8 "In3.Cu" signal "VCC1")
		(10 "In4.Cu" signal "VCC2")
		(12 "In5.Cu" signal "GND2")
		(14 "In6.Cu" signal "IN2")
		(16 "In7.Cu" signal "IN3")
		(18 "In8.Cu" signal "GND3")
		(2 "B.Cu" signal "BOTTOM")
		(9 "F.Adhes" user "F.Adhesive")
		(11 "B.Adhes" user "B.Adhesive")
		(13 "F.Paste" user "Package Geometry/Pastemask Top")
		(15 "B.Paste" user "Package Geometry/Pastemask Bottom")
		(5 "F.SilkS" user "Ref Des/Silkscreen Top")
		(7 "B.SilkS" user "Ref Des/Silkscreen Bottom")
		(1 "F.Mask" user "Board Geometry/Soldermask Top")
		(3 "B.Mask" user "Board Geometry/Soldermask Bottom")
		(17 "Dwgs.User" user "User.Drawings")
		(19 "Cmts.User" user "User.Comments")
		(21 "Eco1.User" user "User.Eco1")
		(23 "Eco2.User" user "User.Eco2")
		(25 "Edge.Cuts" user "Board Geometry/Outline")
		(27 "Margin" user)
		(31 "F.CrtYd" user "Package Geometry/Place Bound Top")
		(29 "B.CrtYd" user "Package Geometry/Place Bound Bottom")
		(35 "F.Fab" user "Ref Des/Assembly Top")
		(33 "B.Fab" user "Ref Des/Assembly Bottom")
	)
	(footprint ""
		(layer "F.Cu")
		(at 169.649394 -36.938712)
		(property "Reference" "R265"
			(at -1.495806 2.202942 0)
			(unlocked yes)
			(layer "F.SilkS")
			(effects
				(font
					(size 0.7874 0.5842)
					(thickness 0.1524)
				)
				(justify left)
			)
		)
		(property "Value" ""
			(at 0 0 0)
			(layer "F.Fab")
			(effects
				(font
					(size 1.27 1.27)
				)
			)
		)
		(duplicate_pad_numbers_are_jumpers no)
		(fp_line
			(start -0.7874 -0.4064)
			(end 0.7874 -0.4064)
			(stroke
				(width 0.1524)
				(type default)
			)
			(layer "F.SilkS")
		)
		(fp_line
			(start -0.7874 0.4064)
			(end -0.7874 -0.4064)
			(stroke
				(width 0.1524)
				(type default)
			)
			(layer "F.SilkS")
		)
		(fp_line
			(start 0.7874 -0.4064)
			(end 0.7874 0.4064)
			(stroke
				(width 0.1524)
				(type default)
			)
			(layer "F.SilkS")
		)
		(fp_line
			(start 0.7874 0.4064)
			(end -0.7874 0.4064)
			(stroke
				(width 0.1524)
				(type default)
			)
			(layer "F.SilkS")
		)
		(fp_poly
			(pts
				(xy -0.508 0.2794) (xy -0.508 0.2286) (xy -0.635 0.2286) (xy -0.635 -0.254) (xy -0.5334 -0.254)
				(xy -0.5334 -0.2794) (xy 0.5334 -0.2794) (xy 0.5334 -0.254) (xy 0.635 -0.254) (xy 0.635 0.254) (xy 0.5334 0.254)
				(xy 0.5334 0.2794)
			)
			(stroke
				(width 0)
				(type default)
			)
			(fill no)
			(layer "F.CrtYd")
		)
		(pad "1" smd rect
			(at 0.40005 0)
			(size 0.4572 0.508)
			(layers "F.Cu" "F.Mask" "F.Paste")
			(net "USB0_L_DN")
		)
		(pad "2" smd rect
			(at -0.40005 0)
			(size 0.4572 0.508)
			(layers "F.Cu" "F.Mask" "F.Paste")
			(net "USB0_DN")
		)
	)
	(footprint ""
		(layer "F.Cu")
		(at 56.084216 -170.630088)
		(property "Reference" "C620"
			(at -9.010142 131.070096 0)
			(unlocked yes)
			(layer "F.SilkS")
			(effects
				(font
					(size 0.7874 0.5842)
					(thickness 0.1524)
				)
				(justify left)
			)
		)
		(property "Value" ""
			(at 0 0 0)
			(layer "F.Fab")
			(effects
				(font
					(size 1.27 1.27)
				)
			)
		)
		(duplicate_pad_numbers_are_jumpers no)
		(fp_line
			(start -0.7874 -0.4064)
			(end 0.7874 -0.4064)
			(stroke
				(width 0.1524)
				(type default)
			)
			(layer "F.SilkS")
		)
		(fp_line
			(start -0.7874 0.4064)
			(end -0.7874 -0.4064)
			(stroke
				(width 0.1524)
				(type default)
			)
			(layer "F.SilkS")
		)
		(fp_line
			(start 0 0.381)
			(end 0 -0.381)
			(stroke
				(width 0.1524)
				(type default)
			)
			(layer "F.SilkS")
		)
		(fp_line
			(start 0.7874 -0.4064)
			(end 0.7874 0.4064)
			(stroke
				(width 0.1524)
				(type default)
			)
			(layer "F.SilkS")
		)
		(fp_line
			(start 0.7874 0.4064)
			(end -0.7874 0.4064)
			(stroke
				(width 0.1524)
				(type default)
			)
			(layer "F.SilkS")
		)
		(fp_poly
			(pts
				(xy -0.5334 0.254) (xy -0.635 0.254) (xy -0.635 0.2286) (xy -0.635 -0.254) (xy -0.5334 -0.254) (xy -0.5334 -0.2794)
				(xy 0.5334 -0.2794) (xy 0.5334 -0.254) (xy 0.635 -0.254) (xy 0.635 0.254) (xy 0.5334 0.254) (xy 0.5334 0.2794)
				(xy -0.508 0.2794) (xy -0.5334 0.2794)
			)
			(stroke
				(width 0)
				(type default)
			)
			(fill no)
			(layer "F.CrtYd")
		)
		(pad "1" smd rect
			(at 0.40005 0)
			(size 0.4572 0.508)
			(layers "F.Cu" "F.Mask" "F.Paste")
			(net "P3V3_NODE1")
		)
		(pad "2" smd rect
			(at -0.40005 0)
			(size 0.4572 0.508)
			(layers "F.Cu" "F.Mask" "F.Paste")
			(net "GND")
		)
	)
	(footprint ""
		(layer "F.Cu")
		(at 15.920466 -74.465434 -90)
		(property "Reference" "CD1"
			(at -1.393698 1.763776 0)
			(unlocked yes)
			(layer "F.SilkS")
			(effects
				(font
					(size 0.7874 0.5842)
					(thickness 0.1524)
				)
				(justify left)
			)
		)
		(property "Value" ""
			(at 0 0 270)
			(layer "F.Fab")
			(effects
				(font
					(size 1.27 1.27)
				)
			)
		)
		(duplicate_pad_numbers_are_jumpers no)
		(fp_line
			(start -0.674878 2.203196)
			(end 0.674878 2.203196)
			(stroke
				(width 0.1524)
				(type default)
			)
			(layer "F.SilkS")
		)
		(fp_line
			(start 0.674878 2.203196)
			(end 0.674878 -1.623822)
			(stroke
				(width 0.1524)
				(type default)
			)
			(layer "F.SilkS")
		)
		(fp_line
			(start -0.40005 0.299974)
			(end 0.40005 0.299974)
			(stroke
				(width 0.1524)
				(type default)
			)
			(layer "F.SilkS")
		)
		(fp_line
			(start 0 0.299974)
			(end 0 0.49911)
			(stroke
				(width 0.1524)
				(type default)
			)
			(layer "F.SilkS")
		)
		(fp_line
			(start 0 0.299974)
			(end -0.40005 -0.299974)
			(stroke
				(width 0.1524)
				(type default)
			)
			(layer "F.SilkS")
		)
		(fp_line
			(start -0.40005 -0.299974)
			(end 0.40005 -0.299974)
			(stroke
				(width 0.1524)
				(type default)
			)
			(layer "F.SilkS")
		)
		(fp_line
			(start 0.40005 -0.299974)
			(end 0 0.299974)
			(stroke
				(width 0.1524)
				(type default)
			)
			(layer "F.SilkS")
		)
		(fp_line
			(start 0 -0.49911)
			(end 0 -0.299974)
			(stroke
				(width 0.1524)
				(type default)
			)
			(layer "F.SilkS")
		)
		(fp_line
			(start -0.674878 -1.623822)
			(end -0.674878 2.203196)
			(stroke
				(width 0.1524)
				(type default)
			)
			(layer "F.SilkS")
		)
		(fp_line
			(start 0.674878 -1.623822)
			(end -0.674878 -1.623822)
			(stroke
				(width 0.1524)
				(type default)
			)
			(layer "F.SilkS")
		)
		(fp_poly
			(pts
				(xy 0.674878 1.549146) (xy 0.674878 2.203196) (xy -0.674878 2.203196) (xy -0.674878 1.549146)
			)
			(stroke
				(width 0)
				(type default)
			)
			(fill yes)
			(layer "F.SilkS")
		)
		(fp_poly
			(pts
				(xy -0.508 1.527302) (xy -0.508 0.975106) (xy -0.674878 0.975106) (xy -0.674878 -0.975106) (xy -0.508 -0.975106)
				(xy -0.508 -1.527302) (xy 0.508 -1.527302) (xy 0.508 -0.975106) (xy 0.674878 -0.975106) (xy 0.674878 0.975106)
				(xy 0.508 0.975106) (xy 0.508 1.527302)
			)
			(stroke
				(width 0)
				(type default)
			)
			(fill no)
			(layer "F.CrtYd")
		)
		(fp_line
			(start -0.674878 0.975106)
			(end 0.674878 0.975106)
			(stroke
				(width 0.1)
				(type default)
			)
			(layer "F.Fab")
		)
		(fp_line
			(start 0.674878 0.975106)
			(end 0.674878 -0.975106)
			(stroke
				(width 0.1)
				(type default)
			)
			(layer "F.Fab")
		)
		(fp_line
			(start -0.40005 0.299974)
			(end 0.40005 0.299974)
			(stroke
				(width 0.1)
				(type default)
			)
			(layer "F.Fab")
		)
		(fp_line
			(start 0 0.299974)
			(end 0 0.49911)
			(stroke
				(width 0.1)
				(type default)
			)
			(layer "F.Fab")
		)
		(fp_line
			(start 0 0.299974)
			(end -0.40005 -0.299974)
			(stroke
				(width 0.1)
				(type default)
			)
			(layer "F.Fab")
		)
		(fp_line
			(start -0.40005 -0.299974)
			(end 0.40005 -0.299974)
			(stroke
				(width 0.1)
				(type default)
			)
			(layer "F.Fab")
		)
		(fp_line
			(start 0.40005 -0.299974)
			(end 0 0.299974)
			(stroke
				(width 0.1)
				(type default)
			)
			(layer "F.Fab")
		)
		(fp_line
			(start 0 -0.49911)
			(end 0 -0.299974)
			(stroke
				(width 0.1)
				(type default)
			)
			(layer "F.Fab")
		)
		(fp_line
			(start -0.674878 -0.975106)
			(end -0.674878 0.975106)
			(stroke
				(width 0.1)
				(type default)
			)
			(layer "F.Fab")
		)
		(fp_line
			(start 0.674878 -0.975106)
			(end -0.674878 -0.975106)
			(stroke
				(width 0.1)
				(type default)
			)
			(layer "F.Fab")
		)
		(fp_text user "-"
			(at -0.260096 3.367024 0)
			(unlocked yes)
			(layer "F.SilkS")
			(effects
				(font
					(size 1.6002 1.1938)
					(thickness 0.1524)
				)
				(justify left)
			)
		)
		(fp_text user "+"
			(at -2.348738 -0.525018 0)
			(unlocked yes)
			(layer "F.SilkS")
			(effects
				(font
					(size 1.6002 1.1938)
					(thickness 0.1524)
				)
				(justify left)
			)
		)
		(fp_text user "-"
			(at -0.5969 2.313178 270)
			(unlocked yes)
			(layer "F.Fab")
			(effects
				(font
					(size 1.6002 1.1938)
					(thickness 0.000001)
				)
				(justify left)
			)
		)
		(pad "1" smd rect
			(at 0 -1.070102)
			(size 0.8128 0.9144)
			(layers "F.Cu" "F.Mask" "F.Paste")
			(net "VCC5_CRTXX")
		)
		(pad "2" smd rect
			(at 0 1.070102)
			(size 0.8128 0.9144)
			(layers "F.Cu" "F.Mask" "F.Paste")
			(net "N21581564")
		)
	)
	(footprint ""
		(layer "F.Cu")
		(at 76.802996 -182.171848)
		(property "Reference" "R1075"
			(at -4.798314 0.98933 0)
			(unlocked yes)
			(layer "F.SilkS")
			(effects
				(font
					(size 0.7874 0.5842)
					(thickness 0.1524)
				)
				(justify left)
			)
		)
		(property "Value" ""
			(at 0 0 0)
			(layer "F.Fab")
			(effects
				(font
					(size 1.27 1.27)
				)
			)
		)
		(duplicate_pad_numbers_are_jumpers no)
		(fp_line
			(start -0.7874 -0.4064)
			(end 0.7874 -0.4064)
			(stroke
				(width 0.1524)
				(type default)
			)
			(layer "F.SilkS")
		)
		(fp_line
			(start -0.7874 0.4064)
			(end -0.7874 -0.4064)
			(stroke
				(width 0.1524)
				(type default)
			)
			(layer "F.SilkS")
		)
		(fp_line
			(start 0.7874 -0.4064)
			(end 0.7874 0.4064)
			(stroke
				(width 0.1524)
				(type default)
			)
			(layer "F.SilkS")
		)
		(fp_line
			(start 0.7874 0.4064)
			(end -0.7874 0.4064)
			(stroke
				(width 0.1524)
				(type default)
			)
			(layer "F.SilkS")
		)
		(fp_poly
			(pts
				(xy -0.508 0.2794) (xy -0.508 0.2286) (xy -0.635 0.2286) (xy -0.635 -0.254) (xy -0.5334 -0.254)
				(xy -0.5334 -0.2794) (xy 0.5334 -0.2794) (xy 0.5334 -0.254) (xy 0.635 -0.254) (xy 0.635 0.254) (xy 0.5334 0.254)
				(xy 0.5334 0.2794)
			)
			(stroke
				(width 0)
				(type default)
			)
			(fill no)
			(layer "F.CrtYd")
		)
		(pad "1" smd rect
			(at 0.40005 0)
			(size 0.4572 0.508)
			(layers "F.Cu" "F.Mask" "F.Paste")
			(net "P3V3_NODE1")
		)
		(pad "2" smd rect
			(at -0.40005 0)
			(size 0.4572 0.508)
			(layers "F.Cu" "F.Mask" "F.Paste")
			(net "JTAG_CPLD2_TMS")
		)
	)
	(footprint ""
		(layer "F.Cu")
		(at 57.195466 -161.928556 -90)
		(property "Reference" "R553"
			(at -1.475232 0.055626 90)
			(unlocked yes)
			(layer "F.SilkS")
			(effects
				(font
					(size 0.7874 0.5842)
					(thickness 0.1524)
				)
				(justify left)
			)
		)
		(property "Value" ""
			(at 0 0 270)
			(layer "F.Fab")
			(effects
				(font
					(size 1.27 1.27)
				)
			)
		)
		(duplicate_pad_numbers_are_jumpers no)
		(fp_line
			(start -0.7874 0.4064)
			(end -0.7874 -0.4064)
			(stroke
				(width 0.1524)
				(type default)
			)
			(layer "F.SilkS")
		)
		(fp_line
			(start 0.7874 0.4064)
			(end -0.7874 0.4064)
			(stroke
				(width 0.1524)
				(type default)
			)
			(layer "F.SilkS")
		)
		(fp_line
			(start -0.7874 -0.4064)
			(end 0.7874 -0.4064)
			(stroke
				(width 0.1524)
				(type default)
			)
			(layer "F.SilkS")
		)
		(fp_line
			(start 0.7874 -0.4064)
			(end 0.7874 0.4064)
			(stroke
				(width 0.1524)
				(type default)
			)
			(layer "F.SilkS")
		)
		(fp_poly
			(pts
				(xy -0.508 0.2794) (xy -0.508 0.2286) (xy -0.635 0.2286) (xy -0.635 -0.254) (xy -0.5334 -0.254)
				(xy -0.5334 -0.2794) (xy 0.5334 -0.2794) (xy 0.5334 -0.254) (xy 0.635 -0.254) (xy 0.635 0.254) (xy 0.5334 0.254)
				(xy 0.5334 0.2794)
			)
			(stroke
				(width 0)
				(type default)
			)
			(fill no)
			(layer "F.CrtYd")
		)
		(pad "1" smd rect
			(at 0.40005 0 270)
			(size 0.4572 0.508)
			(layers "F.Cu" "F.Mask" "F.Paste")
			(net "LAN1_NVM_HOLD_N")
		)
		(pad "2" smd rect
			(at -0.40005 0 270)
			(size 0.4572 0.508)
			(layers "F.Cu" "F.Mask" "F.Paste")
			(net "P3V3_NODE1")
		)
	)
	(footprint ""
		(layer "F.Cu")
		(at 101.387656 -161.76625)
		(property "Reference" "Q44"
			(at 87.97925 70.97649 90)
			(unlocked yes)
			(layer "F.SilkS")
			(effects
				(font
					(size 0.7874 0.5842)
					(thickness 0.1524)
				)
			)
		)
		(property "Value" ""
			(at 0 0 0)
			(layer "F.Fab")
			(effects
				(font
					(size 1.27 1.27)
				)
			)
		)
		(duplicate_pad_numbers_are_jumpers no)
		(fp_line
			(start -1.488186 -1.500124)
			(end 1.488186 -1.500124)
			(stroke
				(width 0.1524)
				(type default)
			)
			(layer "F.SilkS")
		)
		(fp_line
			(start -1.488186 1.500124)
			(end -1.488186 -1.500124)
			(stroke
				(width 0.1524)
				(type default)
			)
			(layer "F.SilkS")
		)
		(fp_line
			(start 1.488186 -1.500124)
			(end 1.488186 1.500124)
			(stroke
				(width 0.1524)
				(type default)
			)
			(layer "F.SilkS")
		)
		(fp_line
			(start 1.488186 1.500124)
			(end -1.488186 1.500124)
			(stroke
				(width 0.1524)
				(type default)
			)
			(layer "F.SilkS")
		)
		(fp_poly
			(pts
				(xy -0.700024 1.500124) (xy 0.700024 1.500124) (xy 0.700024 0.3556) (xy 1.4224 0.3556) (xy 1.4224 -0.3556)
				(xy 0.700024 -0.3556) (xy 0.700024 -1.500124) (xy -0.700024 -1.500124) (xy -0.700024 -1.3208) (xy -1.4224 -1.3208)
				(xy -1.4224 -0.5842) (xy -0.700024 -0.5842) (xy -0.700024 0.5842) (xy -1.4224 0.5842) (xy -1.4224 1.3208)
				(xy -0.700024 1.3208)
			)
			(stroke
				(width 0)
				(type default)
			)
			(fill no)
			(layer "F.CrtYd")
		)
		(fp_line
			(start -0.700024 -1.500124)
			(end 0.700024 -1.500124)
			(stroke
				(width 0.1)
				(type default)
			)
			(layer "F.Fab")
		)
		(fp_line
			(start -0.700024 1.500124)
			(end -0.700024 -1.500124)
			(stroke
				(width 0.1)
				(type default)
			)
			(layer "F.Fab")
		)
		(fp_line
			(start 0.700024 -1.500124)
			(end 0.700024 1.500124)
			(stroke
				(width 0.1)
				(type default)
			)
			(layer "F.Fab")
		)
		(fp_line
			(start 0.700024 1.500124)
			(end -0.700024 1.500124)
			(stroke
				(width 0.1)
				(type default)
			)
			(layer "F.Fab")
		)
		(fp_text user "2"
			(at -1.830832 1.08839 0)
			(unlocked yes)
			(layer "F.SilkS")
			(effects
				(font
					(size 0.635 0.4064)
					(thickness 0.1524)
				)
			)
		)
		(fp_text user "1"
			(at -1.662684 -1.338834 0)
			(unlocked yes)
			(layer "F.SilkS")
			(effects
				(font
					(size 0.635 0.4064)
					(thickness 0.1524)
				)
			)
		)
		(fp_text user "3"
			(at 0.932942 0.999998 0)
			(unlocked yes)
			(layer "F.SilkS")
			(effects
				(font
					(size 0.635 0.4064)
					(thickness 0.1524)
				)
			)
		)
		(fp_text user "1"
			(at -0.90805 -1.8034 270)
			(unlocked yes)
			(layer "F.Fab")
			(effects
				(font
					(size 0.7874 0.5842)
					(thickness 0.000001)
				)
			)
		)
		(fp_text user "2"
			(at -0.90805 1.8542 270)
			(unlocked yes)
			(layer "F.Fab")
			(effects
				(font
					(size 0.7874 0.5842)
					(thickness 0.000001)
				)
			)
		)
		(fp_text user "3"
			(at 2.15773 0 270)
			(unlocked yes)
			(layer "F.Fab")
			(effects
				(font
					(size 0.7874 0.5842)
					(thickness 0.000001)
				)
			)
		)
		(pad "1" smd rect
			(at -0.999998 -0.94996 270)
			(size 0.6096 0.7112)
			(layers "F.Cu" "F.Mask" "F.Paste")
			(net "N52411069")
		)
		(pad "2" smd rect
			(at -0.999998 0.94996 270)
			(size 0.6096 0.7112)
			(layers "F.Cu" "F.Mask" "F.Paste")
			(net "N52411102")
		)
		(pad "3" smd rect
			(at 0.999998 0 270)
			(size 0.6096 0.7112)
			(layers "F.Cu" "F.Mask" "F.Paste")
			(net "POWER_SW1_PWR_CTR_12V")
		)
	)
	(footprint ""
		(layer "F.Cu")
		(at 141.208252 -25.812242 90)
		(property "Reference" "C482"
			(at -10.732008 4.18719 90)
			(unlocked yes)
			(layer "F.SilkS")
			(effects
				(font
					(size 0.7874 0.5842)
					(thickness 0.1524)
				)
				(justify left)
			)
		)
		(property "Value" ""
			(at 0 0 90)
			(layer "F.Fab")
			(effects
				(font
					(size 1.27 1.27)
				)
			)
		)
		(duplicate_pad_numbers_are_jumpers no)
		(fp_line
			(start 0.7874 -0.4064)
			(end 0.7874 0.4064)
			(stroke
				(width 0.1524)
				(type default)
			)
			(layer "F.SilkS")
		)
		(fp_line
			(start -0.7874 -0.4064)
			(end 0.7874 -0.4064)
			(stroke
				(width 0.1524)
				(type default)
			)
			(layer "F.SilkS")
		)
		(fp_line
			(start 0 0.381)
			(end 0 -0.381)
			(stroke
				(width 0.1524)
				(type default)
			)
			(layer "F.SilkS")
		)
		(fp_line
			(start 0.7874 0.4064)
			(end -0.7874 0.4064)
			(stroke
				(width 0.1524)
				(type default)
			)
			(layer "F.SilkS")
		)
		(fp_line
			(start -0.7874 0.4064)
			(end -0.7874 -0.4064)
			(stroke
				(width 0.1524)
				(type default)
			)
			(layer "F.SilkS")
		)
		(fp_poly
			(pts
				(xy -0.5334 0.254) (xy -0.635 0.254) (xy -0.635 0.2286) (xy -0.635 -0.254) (xy -0.5334 -0.254) (xy -0.5334 -0.2794)
				(xy 0.5334 -0.2794) (xy 0.5334 -0.254) (xy 0.635 -0.254) (xy 0.635 0.254) (xy 0.5334 0.254) (xy 0.5334 0.2794)
				(xy -0.508 0.2794) (xy -0.5334 0.2794)
			)
			(stroke
				(width 0)
				(type default)
			)
			(fill no)
			(layer "F.CrtYd")
		)
		(pad "1" smd rect
			(at 0.40005 0 90)
			(size 0.4572 0.508)
			(layers "F.Cu" "F.Mask" "F.Paste")
			(net "SIO_AVCC")
		)
		(pad "2" smd rect
			(at -0.40005 0 90)
			(size 0.4572 0.508)
			(layers "F.Cu" "F.Mask" "F.Paste")
			(net "GNDA")
		)
	)
)
